# T6G (Grand Teton) — schematic netlist excerpt (pin names and nets, part order shuffled) for the footprints in the layout excerpt that follows; sources: Cadence DE-HDL packaged netlist, KiCad conversion of 04192023_DAF0TMB3IC0_F0TG_MB_C_brd_V02_OCP.brd

PU201  MAX15090BEWIT  MAX15090BEWI+T IC  pkg BGA28_0-5_3-525X2-065  page 140
  ISENSE  = P12V_OCP_SENSE_2
  VCC  = P12V_OCP_VCC_2
  IN_A3  = P12V_AUX
  OUT_A4  = P12V_OCP_V3_2
  IN_A5  = P12V_AUX
  GATE  = P12V_OCP_GATE_2
  CDLY  = GND
  CB  = P12V_OCP_CB_2
  GND_B2  = GND
  IN_B3  = P12V_AUX
  OUT_B4  = P12V_OCP_V3_2
  IN_B5  = P12V_AUX
  OUT_B6  = P12V_OCP_V3_2
  \en#\  = GND
  GND_C1  = GND
  GND_C2  = GND
  IN_C3  = P12V_AUX
  OUT_C4  = P12V_OCP_V3_2
  IN_C5  = P12V_AUX
  OUT_C6  = P12V_OCP_V3_2
  \fault#\  = P12V_OCP_FAULT_2
  REG  = P12V_OCP_REG_2
  UV  = P12V_OCP_UV_2
  OV  = P12V_OCP_OV_2
  OUT_D4  = P12V_OCP_V3_2
  IN_D5  = P12V_AUX
  OUT_D6  = P12V_OCP_V3_2
  PG  = P12V_OCP_PWRGD_2

(kicad_pcb
	(version 20260206)
	(generator "pcbnew")
	(generator_version "10.0")
	(general
		(thickness 1.6)
		(legacy_teardrops no)
	)
	(paper "A4")
	(title_block
		(title "04192023_DAF0TMB3IC0_F0TG_MB_C_brd_V02_OCP.brd")
		(comment 1 "Grand Teton / footprints 2554-2554 of 8354")
	)
	(layers
		(0 "F.Cu" signal "TOP")
		(4 "In1.Cu" signal "GND")
		(6 "In2.Cu" signal "IN1")
		(8 "In3.Cu" signal "GND1")
		(10 "In4.Cu" signal "IN2")
		(12 "In5.Cu" signal "GND2")
		(14 "In6.Cu" signal "IN3")
		(16 "In7.Cu" signal "GND3")
		(18 "In8.Cu" signal "VCC")
		(20 "In9.Cu" signal "VCC1")
		(22 "In10.Cu" signal "GND4")
		(24 "In11.Cu" signal "IN4")
		(26 "In12.Cu" signal "GND5")
		(28 "In13.Cu" signal "IN5")
		(30 "In14.Cu" signal "GND6")
		(32 "In15.Cu" signal "IN6")
		(34 "In16.Cu" signal "GND7")
		(2 "B.Cu" signal "BOTTOM")
		(9 "F.Adhes" user "F.Adhesive")
		(11 "B.Adhes" user "B.Adhesive")
		(13 "F.Paste" user "Package Geometry/Pastemask Top")
		(15 "B.Paste" user "Package Geometry/Pastemask Bottom")
		(5 "F.SilkS" user "Ref Des/Silkscreen Top")
		(7 "B.SilkS" user "Ref Des/Silkscreen Bottom")
		(1 "F.Mask" user "Board Geometry/Soldermask Top")
		(3 "B.Mask" user "Board Geometry/Soldermask Bottom")
		(17 "Dwgs.User" user "User.Drawings")
		(19 "Cmts.User" user "User.Comments")
		(21 "Eco1.User" user "User.Eco1")
		(23 "Eco2.User" user "User.Eco2")
		(25 "Edge.Cuts" user "Board Geometry/Outline")
		(27 "Margin" user)
		(31 "F.CrtYd" user "Package Geometry/Place Bound Top")
		(29 "B.CrtYd" user "Package Geometry/Place Bound Bottom")
		(35 "F.Fab" user "Ref Des/Assembly Top")
		(33 "B.Fab" user "Ref Des/Assembly Bottom")
	)
	(footprint ""
		(layer "F.Cu")
		(at 79.356458 -20.694142)
		(property "Reference" "PU201"
			(at 2.898394 -1.895856 0)
			(unlocked yes)
			(layer "F.SilkS")
			(effects
				(font
					(size 0.7874 0.5842)
					(thickness 0.1524)
				)
				(justify left)
			)
		)
		(property "Value" ""
			(at 0 0 0)
			(layer "F.Fab")
			(effects
				(font
					(size 1.27 1.27)
				)
			)
		)
		(duplicate_pad_numbers_are_jumpers no)
		(fp_line
			(start -1.774952 -1.039876)
			(end -1.774952 1.039876)
			(stroke
				(width 0.1524)
				(type default)
			)
			(layer "F.SilkS")
		)
		(fp_line
			(start -1.774952 1.039876)
			(end 1.774952 1.039876)
			(stroke
				(width 0.1524)
				(type default)
			)
			(layer "F.SilkS")
		)
		(fp_line
			(start 1.774952 -1.039876)
			(end -1.774952 -1.039876)
			(stroke
				(width 0.1524)
				(type default)
			)
			(layer "F.SilkS")
		)
		(fp_line
			(start 1.774952 1.039876)
			(end 1.774952 -1.039876)
			(stroke
				(width 0.1524)
				(type default)
			)
			(layer "F.SilkS")
		)
		(fp_poly
			(pts
				(xy -0.999998 -1.801876) (xy -0.999998 -1.039876) (xy -1.769872 -1.039876) (xy -1.769872 -0.249936)
				(xy -2.531872 -0.249936) (xy -2.531872 -1.801876)
			)
			(stroke
				(width 0)
				(type default)
			)
			(fill yes)
			(layer "F.SilkS")
		)
		(fp_line
			(start -1.769872 -1.039876)
			(end -1.769872 1.039876)
			(stroke
				(width 0.1)
				(type default)
			)
			(layer "F.Fab")
		)
		(fp_line
			(start -1.769872 1.039876)
			(end 1.769872 1.039876)
			(stroke
				(width 0.1)
				(type default)
			)
			(layer "F.Fab")
		)
		(fp_line
			(start 1.769872 -1.039876)
			(end -1.769872 -1.039876)
			(stroke
				(width 0.1)
				(type default)
			)
			(layer "F.Fab")
		)
		(fp_line
			(start 1.769872 1.039876)
			(end 1.769872 -1.039876)
			(stroke
				(width 0.1)
				(type default)
			)
			(layer "F.Fab")
		)
		(fp_poly
			(pts
				(xy -1.769872 -1.039876) (xy -0.999998 -1.039876) (xy -0.999998 -1.801876) (xy -2.531872 -1.801876)
				(xy -2.531872 -0.249936) (xy -1.769872 -0.249936)
			)
			(stroke
				(width 0)
				(type default)
			)
			(fill yes)
			(layer "F.Fab")
		)
		(pad "A1" smd circle
			(at -1.500124 -0.750062)
			(size 0.2286 0.2286)
			(layers "F.Cu" "F.Mask" "F.Paste")
			(net "P12V_OCP_SENSE_2")
		)
		(pad "A2" smd circle
			(at -0.999998 -0.750062)
			(size 0.2286 0.2286)
			(layers "F.Cu" "F.Mask" "F.Paste")
			(net "P12V_OCP_VCC_2")
		)
		(pad "A3" smd circle
			(at -0.499872 -0.750062)
			(size 0.2286 0.2286)
			(layers "F.Cu" "F.Mask" "F.Paste")
			(net "P12V_AUX")
		)
		(pad "A4" smd circle
			(at 0 -0.750062)
			(size 0.2286 0.2286)
			(layers "F.Cu" "F.Mask" "F.Paste")
			(net "P12V_OCP_V3_2")
		)
		(pad "A5" smd circle
			(at 0.499872 -0.750062)
			(size 0.2286 0.2286)
			(layers "F.Cu" "F.Mask" "F.Paste")
			(net "P12V_AUX")
		)
		(pad "A6" smd circle
			(at 0.999998 -0.750062)
			(size 0.2286 0.2286)
			(layers "F.Cu" "F.Mask" "F.Paste")
			(net "P12V_OCP_GATE_2")
		)
		(pad "A7" smd circle
			(at 1.500124 -0.750062)
			(size 0.2286 0.2286)
			(layers "F.Cu" "F.Mask" "F.Paste")
			(net "GND")
		)
		(pad "B1" smd circle
			(at -1.500124 -0.249936)
			(size 0.2286 0.2286)
			(layers "F.Cu" "F.Mask" "F.Paste")
			(net "P12V_OCP_CB_2")
		)
		(pad "B2" smd circle
			(at -0.999998 -0.249936)
			(size 0.2286 0.2286)
			(layers "F.Cu" "F.Mask" "F.Paste")
			(net "GND")
		)
		(pad "B3" smd circle
			(at -0.499872 -0.249936)
			(size 0.2286 0.2286)
			(layers "F.Cu" "F.Mask" "F.Paste")
			(net "P12V_AUX")
		)
		(pad "B4" smd circle
			(at 0 -0.249936)
			(size 0.2286 0.2286)
			(layers "F.Cu" "F.Mask" "F.Paste")
			(net "P12V_OCP_V3_2")
		)
		(pad "B5" smd circle
			(at 0.499872 -0.249936)
			(size 0.2286 0.2286)
			(layers "F.Cu" "F.Mask" "F.Paste")
			(net "P12V_AUX")
		)
		(pad "B6" smd circle
			(at 0.999998 -0.249936)
			(size 0.2286 0.2286)
			(layers "F.Cu" "F.Mask" "F.Paste")
			(net "P12V_OCP_V3_2")
		)
		(pad "B7" smd circle
			(at 1.500124 -0.249936)
			(size 0.2286 0.2286)
			(layers "F.Cu" "F.Mask" "F.Paste")
			(net "GND")
		)
		(pad "C1" smd circle
			(at -1.500124 0.249936)
			(size 0.2286 0.2286)
			(layers "F.Cu" "F.Mask" "F.Paste")
			(net "GND")
		)
		(pad "C2" smd circle
			(at -0.999998 0.249936)
			(size 0.2286 0.2286)
			(layers "F.Cu" "F.Mask" "F.Paste")
			(net "GND")
		)
		(pad "C3" smd circle
			(at -0.499872 0.249936)
			(size 0.2286 0.2286)
			(layers "F.Cu" "F.Mask" "F.Paste")
			(net "P12V_AUX")
		)
		(pad "C4" smd circle
			(at 0 0.249936)
			(size 0.2286 0.2286)
			(layers "F.Cu" "F.Mask" "F.Paste")
			(net "P12V_OCP_V3_2")
		)
		(pad "C5" smd circle
			(at 0.499872 0.249936)
			(size 0.2286 0.2286)
			(layers "F.Cu" "F.Mask" "F.Paste")
			(net "P12V_AUX")
		)
		(pad "C6" smd circle
			(at 0.999998 0.249936)
			(size 0.2286 0.2286)
			(layers "F.Cu" "F.Mask" "F.Paste")
			(net "P12V_OCP_V3_2")
		)
		(pad "C7" smd circle
			(at 1.500124 0.249936)
			(size 0.2286 0.2286)
			(layers "F.Cu" "F.Mask" "F.Paste")
			(net "P12V_OCP_FAULT_2")
		)
		(pad "D1" smd circle
			(at -1.500124 0.750062)
			(size 0.2286 0.2286)
			(layers "F.Cu" "F.Mask" "F.Paste")
			(net "P12V_OCP_REG_2")
		)
		(pad "D2" smd circle
			(at -0.999998 0.750062)
			(size 0.2286 0.2286)
			(layers "F.Cu" "F.Mask" "F.Paste")
			(net "P12V_OCP_UV_2")
		)
		(pad "D3" smd circle
			(at -0.499872 0.750062)
			(size 0.2286 0.2286)
			(layers "F.Cu" "F.Mask" "F.Paste")
			(net "P12V_OCP_OV_2")
		)
		(pad "D4" smd circle
			(at 0 0.750062)
			(size 0.2286 0.2286)
			(layers "F.Cu" "F.Mask" "F.Paste")
			(net "P12V_OCP_V3_2")
		)
		(pad "D5" smd circle
			(at 0.499872 0.750062)
			(size 0.2286 0.2286)
			(layers "F.Cu" "F.Mask" "F.Paste")
			(net "P12V_AUX")
		)
		(pad "D6" smd circle
			(at 0.999998 0.750062)
			(size 0.2286 0.2286)
			(layers "F.Cu" "F.Mask" "F.Paste")
			(net "P12V_OCP_V3_2")
		)
		(pad "D7" smd circle
			(at 1.500124 0.750062)
			(size 0.2286 0.2286)
			(layers "F.Cu" "F.Mask" "F.Paste")
			(net "P12V_OCP_PWRGD_2")
		)
	)
)
